(kicad_pcb
	(version 20260206)
	(generator "pcbnew")
	(generator_version "10.0")
	(general
		(thickness 1.6)
		(legacy_teardrops no)
	)
	(paper "A4")
	(title_block
		(title "04192023_DAF0TMB3IC0_F0TG_MB_C_brd_V02_OCP.brd")
		(comment 1 "Grand Teton / footprints 3613-3620 of 8354")
	)
	(layers
		(0 "F.Cu" signal "TOP")
		(4 "In1.Cu" signal "GND")
		(6 "In2.Cu" signal "IN1")
		(8 "In3.Cu" signal "GND1")
		(10 "In4.Cu" signal "IN2")
		(12 "In5.Cu" signal "GND2")
		(14 "In6.Cu" signal "IN3")
		(16 "In7.Cu" signal "GND3")
		(18 "In8.Cu" signal "VCC")
		(20 "In9.Cu" signal "VCC1")
		(22 "In10.Cu" signal "GND4")
		(24 "In11.Cu" signal "IN4")
		(26 "In12.Cu" signal "GND5")
		(28 "In13.Cu" signal "IN5")
		(30 "In14.Cu" signal "GND6")
		(32 "In15.Cu" signal "IN6")
		(34 "In16.Cu" signal "GND7")
		(2 "B.Cu" signal "BOTTOM")
		(9 "F.Adhes" user "F.Adhesive")
		(11 "B.Adhes" user "B.Adhesive")
		(13 "F.Paste" user "Package Geometry/Pastemask Top")
		(15 "B.Paste" user "Package Geometry/Pastemask Bottom")
		(5 "F.SilkS" user "Ref Des/Silkscreen Top")
		(7 "B.SilkS" user "Ref Des/Silkscreen Bottom")
		(1 "F.Mask" user "Board Geometry/Soldermask Top")
		(3 "B.Mask" user "Board Geometry/Soldermask Bottom")
		(17 "Dwgs.User" user "User.Drawings")
		(19 "Cmts.User" user "User.Comments")
		(21 "Eco1.User" user "User.Eco1")
		(23 "Eco2.User" user "User.Eco2")
		(25 "Edge.Cuts" user "Board Geometry/Outline")
		(27 "Margin" user)
		(31 "F.CrtYd" user "Package Geometry/Place Bound Top")
		(29 "B.CrtYd" user "Package Geometry/Place Bound Bottom")
		(35 "F.Fab" user "Ref Des/Assembly Top")
		(33 "B.Fab" user "Ref Des/Assembly Bottom")
	)
	(footprint ""
		(layer "F.Cu")
		(at 149.649434 -320.717672 180)
		(property "Reference" "R374"
			(at 0 0 180)
			(layer "F.SilkS")
			(hide yes)
			(effects
				(font
					(size 1.27 1.27)
				)
			)
		)
		(property "Value" ""
			(at 0 0 180)
			(layer "F.Fab")
			(effects
				(font
					(size 1.27 1.27)
				)
			)
		)
		(duplicate_pad_numbers_are_jumpers no)
		(fp_line
			(start 0.7874 0.4064)
			(end -0.7874 0.4064)
			(stroke
				(width 0.1524)
				(type default)
			)
			(layer "F.SilkS")
		)
		(fp_line
			(start 0.7874 -0.4064)
			(end 0.7874 0.4064)
			(stroke
				(width 0.1524)
				(type default)
			)
			(layer "F.SilkS")
		)
		(fp_line
			(start -0.7874 0.4064)
			(end -0.7874 -0.4064)
			(stroke
				(width 0.1524)
				(type default)
			)
			(layer "F.SilkS")
		)
		(fp_line
			(start -0.7874 -0.4064)
			(end 0.7874 -0.4064)
			(stroke
				(width 0.1524)
				(type default)
			)
			(layer "F.SilkS")
		)
		(fp_line
			(start 0.67945 0.3048)
			(end 0.120396 0.3048)
			(stroke
				(width 0.1)
				(type default)
			)
			(layer "F.Fab")
		)
		(fp_line
			(start 0.67945 -0.3048)
			(end 0.67945 0.3048)
			(stroke
				(width 0.1)
				(type default)
			)
			(layer "F.Fab")
		)
		(fp_line
			(start 0.12065 -0.2794)
			(end 0.12065 -0.3048)
			(stroke
				(width 0.1)
				(type default)
			)
			(layer "F.Fab")
		)
		(fp_line
			(start 0.12065 -0.3048)
			(end 0.67945 -0.3048)
			(stroke
				(width 0.1)
				(type default)
			)
			(layer "F.Fab")
		)
		(fp_line
			(start 0.120396 0.3048)
			(end 0.120396 0.2794)
			(stroke
				(width 0.1)
				(type default)
			)
			(layer "F.Fab")
		)
		(fp_line
			(start 0.120396 0.2794)
			(end -0.12065 0.2794)
			(stroke
				(width 0.1)
				(type default)
			)
			(layer "F.Fab")
		)
		(fp_line
			(start -0.12065 0.3048)
			(end -0.67945 0.3048)
			(stroke
				(width 0.1)
				(type default)
			)
			(layer "F.Fab")
		)
		(fp_line
			(start -0.12065 0.2794)
			(end -0.12065 0.3048)
			(stroke
				(width 0.1)
				(type default)
			)
			(layer "F.Fab")
		)
		(fp_line
			(start -0.12065 -0.2794)
			(end 0.12065 -0.2794)
			(stroke
				(width 0.1)
				(type default)
			)
			(layer "F.Fab")
		)
		(fp_line
			(start -0.12065 -0.305054)
			(end -0.12065 -0.2794)
			(stroke
				(width 0.1)
				(type default)
			)
			(layer "F.Fab")
		)
		(fp_line
			(start -0.67945 0.3048)
			(end -0.67945 -0.305054)
			(stroke
				(width 0.1)
				(type default)
			)
			(layer "F.Fab")
		)
		(fp_line
			(start -0.67945 -0.305054)
			(end -0.12065 -0.305054)
			(stroke
				(width 0.1)
				(type default)
			)
			(layer "F.Fab")
		)
		(pad "1" smd circle
			(at -0.40005 0 180)
			(size 0 0)
			(layers "F.Cu" "F.Mask" "F.Paste")
			(net "PVDD18_S5_P1")
		)
		(pad "2" smd circle
			(at 0.40005 0 180)
			(size 0 0)
			(layers "F.Cu" "F.Mask" "F.Paste")
			(net "CPU1_VDDBT_RTC_G")
		)
	)
	(footprint ""
		(layer "F.Cu")
		(at 305.796696 -381.41783 -90)
		(property "Reference" "C923"
			(at 0 0 270)
			(layer "F.SilkS")
			(hide yes)
			(effects
				(font
					(size 1.27 1.27)
				)
			)
		)
		(property "Value" ""
			(at 0 0 270)
			(layer "F.Fab")
			(effects
				(font
					(size 1.27 1.27)
				)
			)
		)
		(duplicate_pad_numbers_are_jumpers no)
		(fp_line
			(start -0.299974 0.150114)
			(end -0.299974 -0.150114)
			(stroke
				(width 0.1)
				(type default)
			)
			(layer "F.Fab")
		)
		(fp_line
			(start 0.299974 0.150114)
			(end -0.299974 0.150114)
			(stroke
				(width 0.1)
				(type default)
			)
			(layer "F.Fab")
		)
		(fp_line
			(start -0.299974 -0.150114)
			(end 0.299974 -0.150114)
			(stroke
				(width 0.1)
				(type default)
			)
			(layer "F.Fab")
		)
		(fp_line
			(start 0.299974 -0.150114)
			(end 0.299974 0.150114)
			(stroke
				(width 0.1)
				(type default)
			)
			(layer "F.Fab")
		)
		(pad "1" smd rect
			(at -0.2667 0 270)
			(size 0.3048 0.381)
			(layers "F.Cu" "F.Mask" "F.Paste")
			(net "P5E_CPU0_P0_TX_C_DP<5>")
		)
		(pad "2" smd rect
			(at 0.2667 0 270)
			(size 0.3048 0.381)
			(layers "F.Cu" "F.Mask" "F.Paste")
			(net "P5E_CPU0_P0_TX_DP<5>")
		)
	)
	(footprint ""
		(layer "F.Cu")
		(at 125.38837 -34.021268)
		(property "Reference" "C6020"
			(at 0 0 0)
			(layer "F.SilkS")
			(hide yes)
			(effects
				(font
					(size 1.27 1.27)
				)
			)
		)
		(property "Value" ""
			(at 0 0 0)
			(layer "F.Fab")
			(effects
				(font
					(size 1.27 1.27)
				)
			)
		)
		(duplicate_pad_numbers_are_jumpers no)
		(fp_line
			(start -0.40005 -0.4064)
			(end 0.40005 -0.4064)
			(stroke
				(width 0.1524)
				(type default)
			)
			(layer "F.SilkS")
		)
		(fp_line
			(start 0.40005 0.4064)
			(end -0.40005 0.4064)
			(stroke
				(width 0.1524)
				(type default)
			)
			(layer "F.SilkS")
		)
		(fp_line
			(start -0.6858 -0.3048)
			(end -0.1016 -0.3048)
			(stroke
				(width 0.1)
				(type default)
			)
			(layer "F.Fab")
		)
		(fp_line
			(start -0.6858 0.3048)
			(end -0.6858 -0.3048)
			(stroke
				(width 0.1)
				(type default)
			)
			(layer "F.Fab")
		)
		(fp_line
			(start -0.1016 -0.3048)
			(end -0.1016 -0.2794)
			(stroke
				(width 0.1)
				(type default)
			)
			(layer "F.Fab")
		)
		(fp_line
			(start -0.1016 -0.2794)
			(end 0.1016 -0.2794)
			(stroke
				(width 0.1)
				(type default)
			)
			(layer "F.Fab")
		)
		(fp_line
			(start -0.1016 0.2794)
			(end -0.1016 0.3048)
			(stroke
				(width 0.1)
				(type default)
			)
			(layer "F.Fab")
		)
		(fp_line
			(start -0.1016 0.3048)
			(end -0.6858 0.3048)
			(stroke
				(width 0.1)
				(type default)
			)
			(layer "F.Fab")
		)
		(fp_line
			(start 0.1016 -0.3048)
			(end 0.6858 -0.3048)
			(stroke
				(width 0.1)
				(type default)
			)
			(layer "F.Fab")
		)
		(fp_line
			(start 0.1016 -0.2794)
			(end 0.1016 -0.3048)
			(stroke
				(width 0.1)
				(type default)
			)
			(layer "F.Fab")
		)
		(fp_line
			(start 0.1016 0.2794)
			(end -0.1016 0.2794)
			(stroke
				(width 0.1)
				(type default)
			)
			(layer "F.Fab")
		)
		(fp_line
			(start 0.1016 0.3048)
			(end 0.1016 0.2794)
			(stroke
				(width 0.1)
				(type default)
			)
			(layer "F.Fab")
		)
		(fp_line
			(start 0.6858 -0.3048)
			(end 0.6858 0.3048)
			(stroke
				(width 0.1)
				(type default)
			)
			(layer "F.Fab")
		)
		(fp_line
			(start 0.6858 0.3048)
			(end 0.1016 0.3048)
			(stroke
				(width 0.1)
				(type default)
			)
			(layer "F.Fab")
		)
		(pad "1" smd rect
			(at -0.40005 0 180)
			(size 0.4572 0.508)
			(layers "F.Cu" "F.Mask" "F.Paste")
			(net "USB3_CPU0_BMC_RX_DN")
		)
		(pad "2" smd rect
			(at 0.40005 0 180)
			(size 0.4572 0.508)
			(layers "F.Cu" "F.Mask" "F.Paste")
			(net "USB3_CPU0_BMC_RX_C1_DN")
		)
	)
	(footprint ""
		(layer "F.Cu")
		(at 36.73094 -108.09732 90)
		(property "Reference" "R1049"
			(at 0 0 90)
			(layer "F.SilkS")
			(hide yes)
			(effects
				(font
					(size 1.27 1.27)
				)
			)
		)
		(property "Value" ""
			(at 0 0 90)
			(layer "F.Fab")
			(effects
				(font
					(size 1.27 1.27)
				)
			)
		)
		(duplicate_pad_numbers_are_jumpers no)
		(fp_line
			(start 0.7874 -0.4064)
			(end 0.7874 0.4064)
			(stroke
				(width 0.1524)
				(type default)
			)
			(layer "F.SilkS")
		)
		(fp_line
			(start -0.7874 -0.4064)
			(end 0.7874 -0.4064)
			(stroke
				(width 0.1524)
				(type default)
			)
			(layer "F.SilkS")
		)
		(fp_line
			(start 0.7874 0.4064)
			(end -0.7874 0.4064)
			(stroke
				(width 0.1524)
				(type default)
			)
			(layer "F.SilkS")
		)
		(fp_line
			(start -0.7874 0.4064)
			(end -0.7874 -0.4064)
			(stroke
				(width 0.1524)
				(type default)
			)
			(layer "F.SilkS")
		)
		(fp_line
			(start -0.12065 -0.305054)
			(end -0.12065 -0.2794)
			(stroke
				(width 0.1)
				(type default)
			)
			(layer "F.Fab")
		)
		(fp_line
			(start -0.67945 -0.305054)
			(end -0.12065 -0.305054)
			(stroke
				(width 0.1)
				(type default)
			)
			(layer "F.Fab")
		)
		(fp_line
			(start 0.67945 -0.3048)
			(end 0.67945 0.3048)
			(stroke
				(width 0.1)
				(type default)
			)
			(layer "F.Fab")
		)
		(fp_line
			(start 0.12065 -0.3048)
			(end 0.67945 -0.3048)
			(stroke
				(width 0.1)
				(type default)
			)
			(layer "F.Fab")
		)
		(fp_line
			(start 0.12065 -0.2794)
			(end 0.12065 -0.3048)
			(stroke
				(width 0.1)
				(type default)
			)
			(layer "F.Fab")
		)
		(fp_line
			(start -0.12065 -0.2794)
			(end 0.12065 -0.2794)
			(stroke
				(width 0.1)
				(type default)
			)
			(layer "F.Fab")
		)
		(fp_line
			(start 0.120396 0.2794)
			(end -0.12065 0.2794)
			(stroke
				(width 0.1)
				(type default)
			)
			(layer "F.Fab")
		)
		(fp_line
			(start -0.12065 0.2794)
			(end -0.12065 0.3048)
			(stroke
				(width 0.1)
				(type default)
			)
			(layer "F.Fab")
		)
		(fp_line
			(start 0.67945 0.3048)
			(end 0.120396 0.3048)
			(stroke
				(width 0.1)
				(type default)
			)
			(layer "F.Fab")
		)
		(fp_line
			(start 0.120396 0.3048)
			(end 0.120396 0.2794)
			(stroke
				(width 0.1)
				(type default)
			)
			(layer "F.Fab")
		)
		(fp_line
			(start -0.12065 0.3048)
			(end -0.67945 0.3048)
			(stroke
				(width 0.1)
				(type default)
			)
			(layer "F.Fab")
		)
		(fp_line
			(start -0.67945 0.3048)
			(end -0.67945 -0.305054)
			(stroke
				(width 0.1)
				(type default)
			)
			(layer "F.Fab")
		)
		(pad "1" smd circle
			(at -0.40005 0 90)
			(size 0 0)
			(layers "F.Cu" "F.Mask" "F.Paste")
			(net "P12V_AUX_DSC_G1")
		)
		(pad "2" smd circle
			(at 0.40005 0 90)
			(size 0 0)
			(layers "F.Cu" "F.Mask" "F.Paste")
			(net "GND")
		)
	)
	(footprint ""
		(layer "F.Cu")
		(at 389.248142 -416.899344 -90)
		(property "Reference" "C6578"
			(at 0 0 270)
			(layer "F.SilkS")
			(hide yes)
			(effects
				(font
					(size 1.27 1.27)
				)
			)
		)
		(property "Value" ""
			(at 0 0 270)
			(layer "F.Fab")
			(effects
				(font
					(size 1.27 1.27)
				)
			)
		)
		(duplicate_pad_numbers_are_jumpers no)
		(fp_line
			(start -0.299974 0.150114)
			(end -0.299974 -0.150114)
			(stroke
				(width 0.1)
				(type default)
			)
			(layer "F.Fab")
		)
		(fp_line
			(start 0.299974 0.150114)
			(end -0.299974 0.150114)
			(stroke
				(width 0.1)
				(type default)
			)
			(layer "F.Fab")
		)
		(fp_line
			(start -0.299974 -0.150114)
			(end 0.299974 -0.150114)
			(stroke
				(width 0.1)
				(type default)
			)
			(layer "F.Fab")
		)
		(fp_line
			(start 0.299974 -0.150114)
			(end 0.299974 0.150114)
			(stroke
				(width 0.1)
				(type default)
			)
			(layer "F.Fab")
		)
		(pad "1" smd rect
			(at -0.2667 0 270)
			(size 0.3048 0.381)
			(layers "F.Cu" "F.Mask" "F.Paste")
			(net "P5E_CPU0_P2_TX_BUF_C_DN<6>")
		)
		(pad "2" smd rect
			(at 0.2667 0 270)
			(size 0.3048 0.381)
			(layers "F.Cu" "F.Mask" "F.Paste")
			(net "P5E_CPU0_P2_TX_BUF_DN<6>")
		)
	)
	(footprint ""
		(layer "F.Cu")
		(at 325.740776 -385.364228)
		(property "Reference" "C904"
			(at 0 0 0)
			(layer "F.SilkS")
			(hide yes)
			(effects
				(font
					(size 1.27 1.27)
				)
			)
		)
		(property "Value" ""
			(at 0 0 0)
			(layer "F.Fab")
			(effects
				(font
					(size 1.27 1.27)
				)
			)
		)
		(duplicate_pad_numbers_are_jumpers no)
		(fp_line
			(start -0.299974 -0.150114)
			(end 0.299974 -0.150114)
			(stroke
				(width 0.1)
				(type default)
			)
			(layer "F.Fab")
		)
		(fp_line
			(start -0.299974 0.150114)
			(end -0.299974 -0.150114)
			(stroke
				(width 0.1)
				(type default)
			)
			(layer "F.Fab")
		)
		(fp_line
			(start 0.299974 -0.150114)
			(end 0.299974 0.150114)
			(stroke
				(width 0.1)
				(type default)
			)
			(layer "F.Fab")
		)
		(fp_line
			(start 0.299974 0.150114)
			(end -0.299974 0.150114)
			(stroke
				(width 0.1)
				(type default)
			)
			(layer "F.Fab")
		)
		(pad "1" smd rect
			(at -0.2667 0)
			(size 0.3048 0.381)
			(layers "F.Cu" "F.Mask" "F.Paste")
			(net "P5E_CPU0_P0_TX_C_DN<14>")
		)
		(pad "2" smd rect
			(at 0.2667 0)
			(size 0.3048 0.381)
			(layers "F.Cu" "F.Mask" "F.Paste")
			(net "P5E_CPU0_P0_TX_DN<14>")
		)
	)
	(footprint ""
		(layer "F.Cu")
		(at 350.361504 -345.146122)
		(property "Reference" "PR7"
			(at 0 0 0)
			(layer "F.SilkS")
			(hide yes)
			(effects
				(font
					(size 1.27 1.27)
				)
			)
		)
		(property "Value" ""
			(at 0 0 0)
			(layer "F.Fab")
			(effects
				(font
					(size 1.27 1.27)
				)
			)
		)
		(duplicate_pad_numbers_are_jumpers no)
		(fp_line
			(start -0.7874 -0.4064)
			(end 0.7874 -0.4064)
			(stroke
				(width 0.1524)
				(type default)
			)
			(layer "F.SilkS")
		)
		(fp_line
			(start -0.7874 0.4064)
			(end -0.7874 -0.4064)
			(stroke
				(width 0.1524)
				(type default)
			)
			(layer "F.SilkS")
		)
		(fp_line
			(start 0.7874 -0.4064)
			(end 0.7874 0.4064)
			(stroke
				(width 0.1524)
				(type default)
			)
			(layer "F.SilkS")
		)
		(fp_line
			(start 0.7874 0.4064)
			(end -0.7874 0.4064)
			(stroke
				(width 0.1524)
				(type default)
			)
			(layer "F.SilkS")
		)
		(fp_line
			(start -0.67945 -0.305054)
			(end -0.12065 -0.305054)
			(stroke
				(width 0.1)
				(type default)
			)
			(layer "F.Fab")
		)
		(fp_line
			(start -0.67945 0.3048)
			(end -0.67945 -0.305054)
			(stroke
				(width 0.1)
				(type default)
			)
			(layer "F.Fab")
		)
		(fp_line
			(start -0.12065 -0.305054)
			(end -0.12065 -0.2794)
			(stroke
				(width 0.1)
				(type default)
			)
			(layer "F.Fab")
		)
		(fp_line
			(start -0.12065 -0.2794)
			(end 0.12065 -0.2794)
			(stroke
				(width 0.1)
				(type default)
			)
			(layer "F.Fab")
		)
		(fp_line
			(start -0.12065 0.2794)
			(end -0.12065 0.3048)
			(stroke
				(width 0.1)
				(type default)
			)
			(layer "F.Fab")
		)
		(fp_line
			(start -0.12065 0.3048)
			(end -0.67945 0.3048)
			(stroke
				(width 0.1)
				(type default)
			)
			(layer "F.Fab")
		)
		(fp_line
			(start 0.120396 0.2794)
			(end -0.12065 0.2794)
			(stroke
				(width 0.1)
				(type default)
			)
			(layer "F.Fab")
		)
		(fp_line
			(start 0.120396 0.3048)
			(end 0.120396 0.2794)
			(stroke
				(width 0.1)
				(type default)
			)
			(layer "F.Fab")
		)
		(fp_line
			(start 0.12065 -0.3048)
			(end 0.67945 -0.3048)
			(stroke
				(width 0.1)
				(type default)
			)
			(layer "F.Fab")
		)
		(fp_line
			(start 0.12065 -0.2794)
			(end 0.12065 -0.3048)
			(stroke
				(width 0.1)
				(type default)
			)
			(layer "F.Fab")
		)
		(fp_line
			(start 0.67945 -0.3048)
			(end 0.67945 0.3048)
			(stroke
				(width 0.1)
				(type default)
			)
			(layer "F.Fab")
		)
		(fp_line
			(start 0.67945 0.3048)
			(end 0.120396 0.3048)
			(stroke
				(width 0.1)
				(type default)
			)
			(layer "F.Fab")
		)
		(pad "1" smd circle
			(at -0.40005 0)
			(size 0 0)
			(layers "F.Cu" "F.Mask" "F.Paste")
			(net "PVDDCR_CPU1_P0_LSET6")
		)
		(pad "2" smd circle
			(at 0.40005 0)
			(size 0 0)
			(layers "F.Cu" "F.Mask" "F.Paste")
			(net "GND")
		)
	)
	(footprint ""
		(layer "F.Cu")
		(at 175.300894 -391.34288 180)
		(property "Reference" "R864"
			(at 0 0 180)
			(layer "F.SilkS")
			(hide yes)
			(effects
				(font
					(size 1.27 1.27)
				)
			)
		)
		(property "Value" ""
			(at 0 0 180)
			(layer "F.Fab")
			(effects
				(font
					(size 1.27 1.27)
				)
			)
		)
		(duplicate_pad_numbers_are_jumpers no)
		(fp_line
			(start 0.32512 0.175006)
			(end -0.32512 0.175006)
			(stroke
				(width 0.1)
				(type default)
			)
			(layer "F.Fab")
		)
		(fp_line
			(start 0.32512 -0.175006)
			(end 0.32512 0.175006)
			(stroke
				(width 0.1)
				(type default)
			)
			(layer "F.Fab")
		)
		(fp_line
			(start -0.32512 0.175006)
			(end -0.32512 -0.175006)
			(stroke
				(width 0.1)
				(type default)
			)
			(layer "F.Fab")
		)
		(fp_line
			(start -0.32512 -0.175006)
			(end 0.32512 -0.175006)
			(stroke
				(width 0.1)
				(type default)
			)
			(layer "F.Fab")
		)
		(pad "1" smd rect
			(at -0.2667 0 180)
			(size 0.3048 0.381)
			(layers "F.Cu" "F.Mask" "F.Paste")
			(net "P1V8_CPU1_RT_1D")
		)
		(pad "2" smd rect
			(at 0.2667 0)
			(size 0.3048 0.381)
			(layers "F.Cu" "F.Mask" "F.Paste")
			(net "RT_CPU1_P2_ADDR2")
		)
	)
)
